FILE_TYPE = CONNECTIVITY;
{Allegro Design Entry HDL 17.2-2016 S081 (4005846) 1/11/2022}
"PAGE_NUMBER" = 296;
0"NC";
1"P3V3_AUX\g";
2"P3V3_AUX\g";
3"P3V3_AUX\g";
4"P3V3_AUX\g";
5"P3V3_AUX\g";
6"P3V3_AUX\g";
7"P3V3_AUX\g";
8"P3V3_AUX\g";
9"GND\g";
10"GND\g";
11"GND\g";
12"GND\g";
13"GND\g";
14"GND\g";
15"GND\g";
16"GND\g";
17"GND\g";
18"GND\g";
19"GPU_FPGA_EROT_RECOV_N";
20"GPU_FPGA_EROT_RECOV_BUF_R_N";
21"GPU_FPGA_EROT_RST_BUF_R_N";
22"GPU_FPGA_EROT_RST_N";
23"GPU_NVS_PWR_BRAKE_N";
24"NC_U257_2Y";
25"GPU_NVS_PWR_BRAKE_N_R";
26"GPU_FPGA_EROT_RECOV_BUF_N";
27"GPU_FPGA_EROT_RST_BUF_N";
28"GPU_NVS_PWR_BRAKE_N_BUF";
%"UNIVERSAL_POWER"
"1","(1350,3875)","0","logical_power","I11";
;
HDL_POWER"P3V3_AUX"
CDS_LIB"logical_power";
"A"5;
%"UNIVERSAL_GND"
"1","(1350,3325)","0","logical_power","I12";
;
HDL_POWER"GND"
CDS_LIB"logical_power";
"A"16;
%"Q_CAP"
"1","(1350,3550)","0","pure_quanta","I13";
;
PART_NUMBER"CH4104K1B00"
TOLERANCE"10%"
VOLTAGE"25V"
PACK_TYPE"0402"
VALUE"0.1UF"
MATERIAL"X7R"
$LOCATION"C1963"
CDS_LIB"pure_quanta"
CDS_LOCATION"C1963"
$SEC"1"
CDS_SEC"1";
"B"
$PN"2"16;
"A"
$PN"1"5;
%"74LVC2G07DW7"
"1","(775,3750)","0","pure_quanta","I16";
;
PART_NUMBER"AL002G07003"
VALUE"74LVC2G07DW-7"
PART_TYPE"SMLF"
MATERIAL"IC"
$LOCATION"U255"
CDS_LIB"pure_quanta"
NEEDS_NO_SIZE"TRUE"
CDS_LMAN_SYM_OUTLINE"-175,100,175,-100"
CDS_LOCATION"U255"
$SEC"1"
CDS_SEC"1";
"VCC"
$PN"5"5;
"GND"
$PN"2"13;
"2Y"
$PN"4"21;
"1Y"
$PN"6"25;
"2A"
$PN"3"22;
"1A"
$PN"1"23;
%"UNIVERSAL_GND"
"1","(200,3600)","0","logical_power","I17";
;
HDL_POWER"GND"
CDS_LIB"logical_power";
"A"13;
%"UNIVERSAL_POWER"
"1","(-650,4825)","0","logical_power","I28";
;
HDL_POWER"P3V3_AUX"
CDS_LIB"logical_power";
"A"7;
%"Q_RES"
"2","(-650,4575)","0","pure_quanta","I29";
;
PART_NUMBER"CS24702JB10"
PACK_TYPE"0402LF"
MATERIAL"CHIP"
WATTAGE"1/16W"
TOLERANCE"5%"
VALUE"4.7K"
$LOCATION"R3459"
CDS_LIB"pure_quanta"
CDS_LOCATION"R3459"
$SEC"1"
CDS_SEC"1";
"A"
$PN"1"7;
"B"
$PN"2"23;
%"UNIVERSAL_GND"
"1","(-625,3900)","0","logical_power","I30";
;
HDL_POWER"GND"
CDS_LIB"logical_power";
"A"11;
%"Q_RES"
"2","(-625,4100)","0","pure_quanta","I31";
;
PART_NUMBER"CS41002FB09"
TOLERANCE"1%"
VALUE"100K"
WATTAGE"1/16W"
PACK_TYPE"0402LF"
MATERIAL"EMPTY"
$LOCATION"R3460"
CDS_LIB"pure_quanta"
CDS_LOCATION"R3460"
$SEC"1"
CDS_SEC"1";
"A"
$PN"1"23;
"B"
$PN"2"11;
%"Q_RES"
"2","(1875,4000)","0","pure_quanta","I33";
;
PART_NUMBER"CS41002FB09"
PACK_TYPE"0402LF"
MATERIAL"EMPTY"
WATTAGE"1/16W"
TOLERANCE"1%"
VALUE"100K"
$LOCATION"R3462"
CDS_LIB"pure_quanta"
CDS_LOCATION"R3462"
$SEC"1"
CDS_SEC"1";
"A"
$PN"1"25;
"B"
$PN"2"18;
%"UNIVERSAL_POWER"
"1","(1850,4850)","0","logical_power","I34";
;
HDL_POWER"P3V3_AUX"
CDS_LIB"logical_power";
"A"8;
%"Q_RES"
"2","(1850,4600)","0","pure_quanta","I35";
;
PART_NUMBER"CS35492FB03"
WATTAGE"1/16W"
VALUE"54.9K"
TOLERANCE"1%"
MATERIAL"CHIP"
PACK_TYPE"0402LF"
$LOCATION"R3461"
CDS_LIB"pure_quanta"
CDS_LOCATION"R3461"
$SEC"1"
CDS_SEC"1";
"A"
$PN"1"8;
"B"
$PN"2"25;
%"Q_RES"
"1","(2100,4300)","0","pure_quanta","I37";
;
PART_NUMBER"CS03322FB03"
VALUE"33.2"
PACK_TYPE"0402LF"
MATERIAL"CHIP"
$LOCATION"R3397"
CDS_LIB"pure_quanta"
TOLERANCE"1%"
WATTAGE"1/16W"
CDS_LOCATION"R3397"
$SEC"1"
CDS_SEC"1";
"B"
$PN"2"28;
"A"
$PN"1"25;
%"UNIVERSAL_GND"
"1","(1875,3800)","0","logical_power","I38";
;
CDS_LIB"logical_power"
HDL_POWER"GND";
"A"18;
%"UNIVERSAL_POWER"
"1","(-650,3675)","0","logical_power","I39";
;
HDL_POWER"P3V3_AUX"
CDS_LIB"logical_power";
"A"4;
%"Q_RES"
"2","(-650,3425)","0","pure_quanta","I40";
;
PART_NUMBER"CS24702JB10"
WATTAGE"1/16W"
VALUE"4.7K"
TOLERANCE"5%"
MATERIAL"CHIP"
PACK_TYPE"0402LF"
$LOCATION"R3488"
CDS_LIB"pure_quanta"
CDS_LOCATION"R3488"
$SEC"1"
CDS_SEC"1";
"A"
$PN"1"4;
"B"
$PN"2"22;
%"Q_RES"
"2","(-625,2950)","0","pure_quanta","I42";
;
PART_NUMBER"CS41002FB09"
MATERIAL"EMPTY"
PACK_TYPE"0402LF"
WATTAGE"1/16W"
VALUE"100K"
TOLERANCE"1%"
$LOCATION"R3489"
CDS_LIB"pure_quanta"
CDS_LOCATION"R3489"
$SEC"1"
CDS_SEC"1";
"A"
$PN"1"22;
"B"
$PN"2"10;
%"UNIVERSAL_GND"
"1","(-625,2750)","0","logical_power","I43";
;
CDS_LIB"logical_power"
HDL_POWER"GND";
"A"10;
%"Q_RES"
"1","(2150,3100)","0","pure_quanta","I45";
;
PART_NUMBER"CS03322FB03"
VALUE"33.2"
PACK_TYPE"0402LF"
MATERIAL"CHIP"
$LOCATION"R3496"
CDS_LIB"pure_quanta"
TOLERANCE"1%"
WATTAGE"1/16W"
CDS_LOCATION"R3496"
$SEC"1"
CDS_SEC"1";
"B"
$PN"2"27;
"A"
$PN"1"21;
%"UNIVERSAL_POWER"
"1","(1900,3650)","0","logical_power","I46";
;
HDL_POWER"P3V3_AUX"
CDS_LIB"logical_power";
"A"6;
%"Q_RES"
"2","(1900,3400)","0","pure_quanta","I47";
;
PART_NUMBER"CS35492FB03"
WATTAGE"1/16W"
VALUE"54.9K"
TOLERANCE"1%"
MATERIAL"CHIP"
PACK_TYPE"0402LF"
$LOCATION"R3492"
CDS_LIB"pure_quanta"
CDS_LOCATION"R3492"
$SEC"1"
CDS_SEC"1";
"A"
$PN"1"6;
"B"
$PN"2"21;
%"Q_RES"
"2","(1925,2800)","0","pure_quanta","I48";
;
PART_NUMBER"CS41002FB09"
WATTAGE"1/16W"
TOLERANCE"1%"
VALUE"100K"
MATERIAL"EMPTY"
PACK_TYPE"0402LF"
$LOCATION"R3493"
CDS_LIB"pure_quanta"
CDS_LOCATION"R3493"
$SEC"1"
CDS_SEC"1";
"A"
$PN"1"21;
"B"
$PN"2"17;
%"UNIVERSAL_GND"
"1","(1925,2600)","0","logical_power","I49";
;
CDS_LIB"logical_power"
HDL_POWER"GND";
"A"17;
%"74LVC2G07DW7"
"1","(775,1250)","0","pure_quanta","I50";
;
PART_NUMBER"AL002G07003"
PART_TYPE"SMLF"
VALUE"74LVC2G07DW-7"
MATERIAL"IC"
$LOCATION"U257"
CDS_LIB"pure_quanta"
NEEDS_NO_SIZE"TRUE"
CDS_LMAN_SYM_OUTLINE"-175,100,175,-100"
CDS_LOCATION"U257"
$SEC"1"
CDS_SEC"1";
"VCC"
$PN"5"1;
"GND"
$PN"2"12;
"2Y"
$PN"4"24;
"1Y"
$PN"6"20;
"2A"
$PN"3"12;
"1A"
$PN"1"19;
%"Q_RES"
"1","(2325,1800)","0","pure_quanta","I53";
;
PART_NUMBER"CS03322FB03"
VALUE"33.2"
PACK_TYPE"0402LF"
MATERIAL"CHIP"
$LOCATION"R3497"
CDS_LIB"pure_quanta"
TOLERANCE"1%"
WATTAGE"1/16W"
CDS_LOCATION"R3497"
$SEC"1"
CDS_SEC"1";
"B"
$PN"2"26;
"A"
$PN"1"20;
%"UNIVERSAL_POWER"
"1","(2075,2350)","0","logical_power","I54";
;
HDL_POWER"P3V3_AUX"
CDS_LIB"logical_power";
"A"3;
%"Q_RES"
"2","(2075,2100)","0","pure_quanta","I55";
;
PART_NUMBER"CS35492FB03"
PACK_TYPE"0402LF"
TOLERANCE"1%"
WATTAGE"1/16W"
MATERIAL"CHIP"
VALUE"54.9K"
$LOCATION"R3494"
CDS_LIB"pure_quanta"
CDS_LOCATION"R3494"
$SEC"1"
CDS_SEC"1";
"A"
$PN"1"3;
"B"
$PN"2"20;
%"UNIVERSAL_POWER"
"1","(-650,2325)","0","logical_power","I56";
;
HDL_POWER"P3V3_AUX"
CDS_LIB"logical_power";
"A"2;
%"Q_RES"
"2","(-650,2075)","0","pure_quanta","I57";
;
PART_NUMBER"CS24702JB10"
PACK_TYPE"0402LF"
TOLERANCE"5%"
WATTAGE"1/16W"
MATERIAL"CHIP"
VALUE"4.7K"
$LOCATION"R3490"
CDS_LIB"pure_quanta"
CDS_LOCATION"R3490"
$SEC"1"
CDS_SEC"1";
"A"
$PN"1"2;
"B"
$PN"2"19;
%"Q_RES"
"2","(2100,1500)","0","pure_quanta","I62";
;
PART_NUMBER"CS41002FB09"
VALUE"100K"
PACK_TYPE"0402LF"
WATTAGE"1/16W"
TOLERANCE"1%"
MATERIAL"EMPTY"
$LOCATION"R3495"
CDS_LIB"pure_quanta"
CDS_LOCATION"R3495"
$SEC"1"
CDS_SEC"1";
"A"
$PN"1"20;
"B"
$PN"2"15;
%"UNIVERSAL_GND"
"1","(2100,1300)","0","logical_power","I63";
;
CDS_LIB"logical_power"
HDL_POWER"GND";
"A"15;
%"UNIVERSAL_POWER"
"1","(1350,1375)","0","logical_power","I66";
;
HDL_POWER"P3V3_AUX"
CDS_LIB"logical_power";
"A"1;
%"Q_CAP"
"1","(1350,1050)","0","pure_quanta","I67";
;
PART_NUMBER"CH4104K1B00"
PACK_TYPE"0402"
MATERIAL"X7R"
VOLTAGE"25V"
VALUE"0.1UF"
TOLERANCE"10%"
$LOCATION"C1979"
CDS_LIB"pure_quanta"
CDS_LOCATION"C1979"
$SEC"1"
CDS_SEC"1";
"B"
$PN"2"14;
"A"
$PN"1"1;
%"UNIVERSAL_GND"
"1","(1350,825)","0","logical_power","I68";
;
CDS_LIB"logical_power"
HDL_POWER"GND";
"A"14;
%"UNIVERSAL_GND"
"1","(200,1100)","0","logical_power","I69";
;
CDS_LIB"logical_power"
HDL_POWER"GND";
"A"12;
%"Q_RES"
"2","(-600,1600)","0","pure_quanta","I70";
;
PART_NUMBER"CS41002FB09"
VALUE"100K"
TOLERANCE"1%"
WATTAGE"1/16W"
PACK_TYPE"0402LF"
MATERIAL"EMPTY"
$LOCATION"R3491"
CDS_LIB"pure_quanta"
CDS_LOCATION"R3491"
$SEC"1"
CDS_SEC"1";
"A"
$PN"1"19;
"B"
$PN"2"9;
%"UNIVERSAL_GND"
"1","(-600,1400)","0","logical_power","I74";
;
HDL_POWER"GND"
CDS_LIB"logical_power";
"A"9;
END.
